(kicad_pcb
	(version 20260206)
	(generator "pcbnew")
	(generator_version "10.0")
	(general
		(thickness 1.6)
		(legacy_teardrops no)
	)
	(paper "A4")
	(title_block
		(title "01162023_DA0F0TEBIF0_F0T_Expander_BD_F_brd_V02_OCP.brd")
		(comment 1 "Grand Teton / footprints 7971-7981 of 9728")
	)
	(layers
		(0 "F.Cu" signal "TOP")
		(4 "In1.Cu" signal "GND")
		(6 "In2.Cu" signal "VCC")
		(8 "In3.Cu" signal "VCC1")
		(10 "In4.Cu" signal "GND1")
		(12 "In5.Cu" signal "IN1")
		(14 "In6.Cu" signal "GND2")
		(16 "In7.Cu" signal "IN2")
		(18 "In8.Cu" signal "GND3")
		(20 "In9.Cu" signal "IN3")
		(22 "In10.Cu" signal "GND4")
		(24 "In11.Cu" signal "IN4")
		(26 "In12.Cu" signal "GND5")
		(28 "In13.Cu" signal "IN5")
		(30 "In14.Cu" signal "GND6")
		(32 "In15.Cu" signal "IN6")
		(34 "In16.Cu" signal "GND7")
		(2 "B.Cu" signal "BOTTOM")
		(9 "F.Adhes" user "F.Adhesive")
		(11 "B.Adhes" user "B.Adhesive")
		(13 "F.Paste" user "Package Geometry/Pastemask Top")
		(15 "B.Paste" user "Package Geometry/Pastemask Bottom")
		(5 "F.SilkS" user "Ref Des/Silkscreen Top")
		(7 "B.SilkS" user "Ref Des/Silkscreen Bottom")
		(1 "F.Mask" user "Board Geometry/Soldermask Top")
		(3 "B.Mask" user "Board Geometry/Soldermask Bottom")
		(17 "Dwgs.User" user "User.Drawings")
		(19 "Cmts.User" user "User.Comments")
		(21 "Eco1.User" user "User.Eco1")
		(23 "Eco2.User" user "User.Eco2")
		(25 "Edge.Cuts" user "Board Geometry/Outline")
		(27 "Margin" user)
		(31 "F.CrtYd" user "Package Geometry/Place Bound Top")
		(29 "B.CrtYd" user "Package Geometry/Place Bound Bottom")
		(35 "F.Fab" user "Ref Des/Assembly Top")
		(33 "B.Fab" user "Ref Des/Assembly Bottom")
	)
	(footprint ""
		(layer "B.Cu")
		(at 347.091 -233.553 90)
		(property "Reference" "R3580"
			(at 0 0 90)
			(layer "B.SilkS")
			(hide yes)
			(effects
				(font
					(size 1.27 1.27)
				)
				(justify mirror)
			)
		)
		(property "Value" ""
			(at 0 0 90)
			(layer "B.Fab")
			(effects
				(font
					(size 1.27 1.27)
				)
				(justify mirror)
			)
		)
		(duplicate_pad_numbers_are_jumpers no)
		(fp_line
			(start 0.7874 -0.4064)
			(end -0.7874 -0.4064)
			(stroke
				(width 0.1524)
				(type default)
			)
			(layer "B.SilkS")
		)
		(fp_line
			(start -0.7874 -0.4064)
			(end -0.7874 0.4064)
			(stroke
				(width 0.1524)
				(type default)
			)
			(layer "B.SilkS")
		)
		(fp_line
			(start 0.7874 0.4064)
			(end 0.7874 -0.4064)
			(stroke
				(width 0.1524)
				(type default)
			)
			(layer "B.SilkS")
		)
		(fp_line
			(start -0.7874 0.4064)
			(end 0.7874 0.4064)
			(stroke
				(width 0.1524)
				(type default)
			)
			(layer "B.SilkS")
		)
		(fp_line
			(start 0.67945 -0.305054)
			(end 0.12065 -0.305054)
			(stroke
				(width 0.1)
				(type default)
			)
			(layer "B.Fab")
		)
		(fp_line
			(start 0.12065 -0.305054)
			(end 0.12065 -0.2794)
			(stroke
				(width 0.1)
				(type default)
			)
			(layer "B.Fab")
		)
		(fp_line
			(start -0.12065 -0.3048)
			(end -0.67945 -0.3048)
			(stroke
				(width 0.1)
				(type default)
			)
			(layer "B.Fab")
		)
		(fp_line
			(start -0.67945 -0.3048)
			(end -0.67945 0.3048)
			(stroke
				(width 0.1)
				(type default)
			)
			(layer "B.Fab")
		)
		(fp_line
			(start 0.12065 -0.2794)
			(end -0.12065 -0.2794)
			(stroke
				(width 0.1)
				(type default)
			)
			(layer "B.Fab")
		)
		(fp_line
			(start -0.12065 -0.2794)
			(end -0.12065 -0.3048)
			(stroke
				(width 0.1)
				(type default)
			)
			(layer "B.Fab")
		)
		(fp_line
			(start 0.12065 0.2794)
			(end 0.12065 0.3048)
			(stroke
				(width 0.1)
				(type default)
			)
			(layer "B.Fab")
		)
		(fp_line
			(start -0.120396 0.2794)
			(end 0.12065 0.2794)
			(stroke
				(width 0.1)
				(type default)
			)
			(layer "B.Fab")
		)
		(fp_line
			(start 0.67945 0.3048)
			(end 0.67945 -0.305054)
			(stroke
				(width 0.1)
				(type default)
			)
			(layer "B.Fab")
		)
		(fp_line
			(start 0.12065 0.3048)
			(end 0.67945 0.3048)
			(stroke
				(width 0.1)
				(type default)
			)
			(layer "B.Fab")
		)
		(fp_line
			(start -0.120396 0.3048)
			(end -0.120396 0.2794)
			(stroke
				(width 0.1)
				(type default)
			)
			(layer "B.Fab")
		)
		(fp_line
			(start -0.67945 0.3048)
			(end -0.120396 0.3048)
			(stroke
				(width 0.1)
				(type default)
			)
			(layer "B.Fab")
		)
		(pad "1" smd circle
			(at 0.40005 0 270)
			(size 0 0)
			(layers "B.Cu" "B.Mask" "B.Paste")
			(net "RST_SSD6_PERST_R_N")
		)
		(pad "2" smd circle
			(at -0.40005 0 270)
			(size 0 0)
			(layers "B.Cu" "B.Mask" "B.Paste")
			(net "RST_SSD6_PERST_N")
		)
	)
	(footprint ""
		(layer "B.Cu")
		(at 46.736 -298.27474)
		(property "Reference" "C3069"
			(at 0 0 0)
			(layer "B.SilkS")
			(hide yes)
			(effects
				(font
					(size 1.27 1.27)
				)
				(justify mirror)
			)
		)
		(property "Value" ""
			(at 0 0 0)
			(layer "B.Fab")
			(effects
				(font
					(size 1.27 1.27)
				)
				(justify mirror)
			)
		)
		(duplicate_pad_numbers_are_jumpers no)
		(fp_line
			(start -0.299974 -0.150114)
			(end -0.299974 0.150114)
			(stroke
				(width 0.1)
				(type default)
			)
			(layer "B.Fab")
		)
		(fp_line
			(start -0.299974 0.150114)
			(end 0.299974 0.150114)
			(stroke
				(width 0.1)
				(type default)
			)
			(layer "B.Fab")
		)
		(fp_line
			(start 0.299974 -0.150114)
			(end -0.299974 -0.150114)
			(stroke
				(width 0.1)
				(type default)
			)
			(layer "B.Fab")
		)
		(fp_line
			(start 0.299974 0.150114)
			(end 0.299974 -0.150114)
			(stroke
				(width 0.1)
				(type default)
			)
			(layer "B.Fab")
		)
		(pad "1" smd rect
			(at 0.2667 0 180)
			(size 0.3048 0.381)
			(layers "B.Cu" "B.Mask" "B.Paste")
			(net "SYSPLL_VDDA18_PEX0")
		)
		(pad "2" smd rect
			(at -0.2667 0 180)
			(size 0.3048 0.381)
			(layers "B.Cu" "B.Mask" "B.Paste")
			(net "GND")
		)
	)
	(footprint ""
		(layer "B.Cu")
		(at 50.165 -301.599854 -90)
		(property "Reference" "C1179"
			(at 0 0 90)
			(layer "B.SilkS")
			(hide yes)
			(effects
				(font
					(size 1.27 1.27)
				)
				(justify mirror)
			)
		)
		(property "Value" ""
			(at 0 0 90)
			(layer "B.Fab")
			(effects
				(font
					(size 1.27 1.27)
				)
				(justify mirror)
			)
		)
		(duplicate_pad_numbers_are_jumpers no)
		(fp_line
			(start -0.299974 0.150114)
			(end 0.299974 0.150114)
			(stroke
				(width 0.1)
				(type default)
			)
			(layer "B.Fab")
		)
		(fp_line
			(start 0.299974 0.150114)
			(end 0.299974 -0.150114)
			(stroke
				(width 0.1)
				(type default)
			)
			(layer "B.Fab")
		)
		(fp_line
			(start -0.299974 -0.150114)
			(end -0.299974 0.150114)
			(stroke
				(width 0.1)
				(type default)
			)
			(layer "B.Fab")
		)
		(fp_line
			(start 0.299974 -0.150114)
			(end -0.299974 -0.150114)
			(stroke
				(width 0.1)
				(type default)
			)
			(layer "B.Fab")
		)
		(pad "1" smd rect
			(at 0.2667 0 90)
			(size 0.3048 0.381)
			(layers "B.Cu" "B.Mask" "B.Paste")
			(net "P0V8_SERDES_VDDA_PEX0")
		)
		(pad "2" smd rect
			(at -0.2667 0 90)
			(size 0.3048 0.381)
			(layers "B.Cu" "B.Mask" "B.Paste")
			(net "GND")
		)
	)
	(footprint ""
		(layer "B.Cu")
		(at 250.272296 -345.517724 -90)
		(property "Reference" "R6823"
			(at 0 0 90)
			(layer "B.SilkS")
			(hide yes)
			(effects
				(font
					(size 1.27 1.27)
				)
				(justify mirror)
			)
		)
		(property "Value" ""
			(at 0 0 90)
			(layer "B.Fab")
			(effects
				(font
					(size 1.27 1.27)
				)
				(justify mirror)
			)
		)
		(duplicate_pad_numbers_are_jumpers no)
		(fp_line
			(start -0.7874 0.4064)
			(end 0.7874 0.4064)
			(stroke
				(width 0.1524)
				(type default)
			)
			(layer "B.SilkS")
		)
		(fp_line
			(start 0.7874 0.4064)
			(end 0.7874 -0.4064)
			(stroke
				(width 0.1524)
				(type default)
			)
			(layer "B.SilkS")
		)
		(fp_line
			(start -0.7874 -0.4064)
			(end -0.7874 0.4064)
			(stroke
				(width 0.1524)
				(type default)
			)
			(layer "B.SilkS")
		)
		(fp_line
			(start 0.7874 -0.4064)
			(end -0.7874 -0.4064)
			(stroke
				(width 0.1524)
				(type default)
			)
			(layer "B.SilkS")
		)
		(fp_line
			(start -0.67945 0.3048)
			(end -0.120396 0.3048)
			(stroke
				(width 0.1)
				(type default)
			)
			(layer "B.Fab")
		)
		(fp_line
			(start -0.120396 0.3048)
			(end -0.120396 0.2794)
			(stroke
				(width 0.1)
				(type default)
			)
			(layer "B.Fab")
		)
		(fp_line
			(start 0.12065 0.3048)
			(end 0.67945 0.3048)
			(stroke
				(width 0.1)
				(type default)
			)
			(layer "B.Fab")
		)
		(fp_line
			(start 0.67945 0.3048)
			(end 0.67945 -0.305054)
			(stroke
				(width 0.1)
				(type default)
			)
			(layer "B.Fab")
		)
		(fp_line
			(start -0.120396 0.2794)
			(end 0.12065 0.2794)
			(stroke
				(width 0.1)
				(type default)
			)
			(layer "B.Fab")
		)
		(fp_line
			(start 0.12065 0.2794)
			(end 0.12065 0.3048)
			(stroke
				(width 0.1)
				(type default)
			)
			(layer "B.Fab")
		)
		(fp_line
			(start -0.12065 -0.2794)
			(end -0.12065 -0.3048)
			(stroke
				(width 0.1)
				(type default)
			)
			(layer "B.Fab")
		)
		(fp_line
			(start 0.12065 -0.2794)
			(end -0.12065 -0.2794)
			(stroke
				(width 0.1)
				(type default)
			)
			(layer "B.Fab")
		)
		(fp_line
			(start -0.67945 -0.3048)
			(end -0.67945 0.3048)
			(stroke
				(width 0.1)
				(type default)
			)
			(layer "B.Fab")
		)
		(fp_line
			(start -0.12065 -0.3048)
			(end -0.67945 -0.3048)
			(stroke
				(width 0.1)
				(type default)
			)
			(layer "B.Fab")
		)
		(fp_line
			(start 0.12065 -0.305054)
			(end 0.12065 -0.2794)
			(stroke
				(width 0.1)
				(type default)
			)
			(layer "B.Fab")
		)
		(fp_line
			(start 0.67945 -0.305054)
			(end 0.12065 -0.305054)
			(stroke
				(width 0.1)
				(type default)
			)
			(layer "B.Fab")
		)
		(pad "1" smd circle
			(at 0.40005 0 90)
			(size 0 0)
			(layers "B.Cu" "B.Mask" "B.Paste")
			(net "HSC_TYPE_ADC_R")
		)
		(pad "2" smd circle
			(at -0.40005 0 90)
			(size 0 0)
			(layers "B.Cu" "B.Mask" "B.Paste")
			(net "P12V_AUX")
		)
	)
	(footprint ""
		(layer "B.Cu")
		(at 453.754744 -279.673558 180)
		(property "Reference" "C4401"
			(at 0 0 0)
			(layer "B.SilkS")
			(hide yes)
			(effects
				(font
					(size 1.27 1.27)
				)
				(justify mirror)
			)
		)
		(property "Value" ""
			(at 0 0 0)
			(layer "B.Fab")
			(effects
				(font
					(size 1.27 1.27)
				)
				(justify mirror)
			)
		)
		(duplicate_pad_numbers_are_jumpers no)
		(fp_line
			(start 1.2954 0.5842)
			(end 1.2954 -0.5842)
			(stroke
				(width 0.1524)
				(type default)
			)
			(layer "B.SilkS")
		)
		(fp_line
			(start 1.2954 -0.5842)
			(end -1.2954 -0.5842)
			(stroke
				(width 0.1524)
				(type default)
			)
			(layer "B.SilkS")
		)
		(fp_line
			(start -1.2954 0.5842)
			(end 1.2954 0.5842)
			(stroke
				(width 0.1524)
				(type default)
			)
			(layer "B.SilkS")
		)
		(fp_line
			(start -1.2954 -0.5842)
			(end -1.2954 0.5842)
			(stroke
				(width 0.1524)
				(type default)
			)
			(layer "B.SilkS")
		)
		(fp_line
			(start 1.1938 0.4064)
			(end 1.1938 -0.4064)
			(stroke
				(width 0.1)
				(type default)
			)
			(layer "B.Fab")
		)
		(fp_line
			(start 1.1938 -0.4064)
			(end 0.8636 -0.4064)
			(stroke
				(width 0.1)
				(type default)
			)
			(layer "B.Fab")
		)
		(fp_line
			(start 0.8636 0.4572)
			(end 0.8636 0.4064)
			(stroke
				(width 0.1)
				(type default)
			)
			(layer "B.Fab")
		)
		(fp_line
			(start 0.8636 0.4064)
			(end 1.1938 0.4064)
			(stroke
				(width 0.1)
				(type default)
			)
			(layer "B.Fab")
		)
		(fp_line
			(start 0.8636 -0.4064)
			(end 0.8636 -0.4572)
			(stroke
				(width 0.1)
				(type default)
			)
			(layer "B.Fab")
		)
		(fp_line
			(start 0.8636 -0.4572)
			(end -0.8636 -0.4572)
			(stroke
				(width 0.1)
				(type default)
			)
			(layer "B.Fab")
		)
		(fp_line
			(start -0.8636 0.4572)
			(end 0.8636 0.4572)
			(stroke
				(width 0.1)
				(type default)
			)
			(layer "B.Fab")
		)
		(fp_line
			(start -0.8636 0.4064)
			(end -0.8636 0.4572)
			(stroke
				(width 0.1)
				(type default)
			)
			(layer "B.Fab")
		)
		(fp_line
			(start -0.8636 -0.4064)
			(end -1.1938 -0.4064)
			(stroke
				(width 0.1)
				(type default)
			)
			(layer "B.Fab")
		)
		(fp_line
			(start -0.8636 -0.4572)
			(end -0.8636 -0.4064)
			(stroke
				(width 0.1)
				(type default)
			)
			(layer "B.Fab")
		)
		(fp_line
			(start -1.1938 0.4064)
			(end -0.8636 0.4064)
			(stroke
				(width 0.1)
				(type default)
			)
			(layer "B.Fab")
		)
		(fp_line
			(start -1.1938 -0.4064)
			(end -1.1938 0.4064)
			(stroke
				(width 0.1)
				(type default)
			)
			(layer "B.Fab")
		)
		(pad "1" smd rect
			(at 0.7366 0 90)
			(size 0.7112 0.8128)
			(layers "B.Cu" "B.Mask" "B.Paste")
			(net "P1V25_PEX3")
		)
		(pad "2" smd rect
			(at -0.7366 0 90)
			(size 0.7112 0.8128)
			(layers "B.Cu" "B.Mask" "B.Paste")
			(net "GND")
		)
	)
	(footprint ""
		(layer "B.Cu")
		(at 409.401264 -305.399948 -90)
		(property "Reference" "C3496"
			(at 0 0 90)
			(layer "B.SilkS")
			(hide yes)
			(effects
				(font
					(size 1.27 1.27)
				)
				(justify mirror)
			)
		)
		(property "Value" ""
			(at 0 0 90)
			(layer "B.Fab")
			(effects
				(font
					(size 1.27 1.27)
				)
				(justify mirror)
			)
		)
		(duplicate_pad_numbers_are_jumpers no)
		(fp_line
			(start -0.299974 0.150114)
			(end 0.299974 0.150114)
			(stroke
				(width 0.1)
				(type default)
			)
			(layer "B.Fab")
		)
		(fp_line
			(start 0.299974 0.150114)
			(end 0.299974 -0.150114)
			(stroke
				(width 0.1)
				(type default)
			)
			(layer "B.Fab")
		)
		(fp_line
			(start -0.299974 -0.150114)
			(end -0.299974 0.150114)
			(stroke
				(width 0.1)
				(type default)
			)
			(layer "B.Fab")
		)
		(fp_line
			(start 0.299974 -0.150114)
			(end -0.299974 -0.150114)
			(stroke
				(width 0.1)
				(type default)
			)
			(layer "B.Fab")
		)
		(pad "1" smd rect
			(at 0.2667 0 90)
			(size 0.3048 0.381)
			(layers "B.Cu" "B.Mask" "B.Paste")
			(net "P1V25_SERDES_VDDPLL_PEX3")
		)
		(pad "2" smd rect
			(at -0.2667 0 90)
			(size 0.3048 0.381)
			(layers "B.Cu" "B.Mask" "B.Paste")
			(net "GND")
		)
	)
	(footprint ""
		(layer "B.Cu")
		(at 289.94989 -292.099746 90)
		(property "Reference" "C1708"
			(at 0 0 90)
			(layer "B.SilkS")
			(hide yes)
			(effects
				(font
					(size 1.27 1.27)
				)
				(justify mirror)
			)
		)
		(property "Value" ""
			(at 0 0 90)
			(layer "B.Fab")
			(effects
				(font
					(size 1.27 1.27)
				)
				(justify mirror)
			)
		)
		(duplicate_pad_numbers_are_jumpers no)
		(fp_line
			(start 0.299974 -0.150114)
			(end -0.299974 -0.150114)
			(stroke
				(width 0.1)
				(type default)
			)
			(layer "B.Fab")
		)
		(fp_line
			(start -0.299974 -0.150114)
			(end -0.299974 0.150114)
			(stroke
				(width 0.1)
				(type default)
			)
			(layer "B.Fab")
		)
		(fp_line
			(start 0.299974 0.150114)
			(end 0.299974 -0.150114)
			(stroke
				(width 0.1)
				(type default)
			)
			(layer "B.Fab")
		)
		(fp_line
			(start -0.299974 0.150114)
			(end 0.299974 0.150114)
			(stroke
				(width 0.1)
				(type default)
			)
			(layer "B.Fab")
		)
		(pad "1" smd rect
			(at 0.2667 0 270)
			(size 0.3048 0.381)
			(layers "B.Cu" "B.Mask" "B.Paste")
			(net "P0V8_SERDES_VDDA_PEX2")
		)
		(pad "2" smd rect
			(at -0.2667 0 270)
			(size 0.3048 0.381)
			(layers "B.Cu" "B.Mask" "B.Paste")
			(net "GND")
		)
	)
	(footprint ""
		(layer "B.Cu")
		(at 392.749786 -298.27474)
		(property "Reference" "C3533"
			(at 0 0 0)
			(layer "B.SilkS")
			(hide yes)
			(effects
				(font
					(size 1.27 1.27)
				)
				(justify mirror)
			)
		)
		(property "Value" ""
			(at 0 0 0)
			(layer "B.Fab")
			(effects
				(font
					(size 1.27 1.27)
				)
				(justify mirror)
			)
		)
		(duplicate_pad_numbers_are_jumpers no)
		(fp_line
			(start -0.299974 -0.150114)
			(end -0.299974 0.150114)
			(stroke
				(width 0.1)
				(type default)
			)
			(layer "B.Fab")
		)
		(fp_line
			(start -0.299974 0.150114)
			(end 0.299974 0.150114)
			(stroke
				(width 0.1)
				(type default)
			)
			(layer "B.Fab")
		)
		(fp_line
			(start 0.299974 -0.150114)
			(end -0.299974 -0.150114)
			(stroke
				(width 0.1)
				(type default)
			)
			(layer "B.Fab")
		)
		(fp_line
			(start 0.299974 0.150114)
			(end 0.299974 -0.150114)
			(stroke
				(width 0.1)
				(type default)
			)
			(layer "B.Fab")
		)
		(pad "1" smd rect
			(at 0.2667 0 180)
			(size 0.3048 0.381)
			(layers "B.Cu" "B.Mask" "B.Paste")
			(net "P1V8_VDDA_PEX3")
		)
		(pad "2" smd rect
			(at -0.2667 0 180)
			(size 0.3048 0.381)
			(layers "B.Cu" "B.Mask" "B.Paste")
			(net "GND")
		)
	)
	(footprint ""
		(layer "B.Cu")
		(at 160.549844 -293.04996)
		(property "Reference" "C3178"
			(at 0 0 0)
			(layer "B.SilkS")
			(hide yes)
			(effects
				(font
					(size 1.27 1.27)
				)
				(justify mirror)
			)
		)
		(property "Value" ""
			(at 0 0 0)
			(layer "B.Fab")
			(effects
				(font
					(size 1.27 1.27)
				)
				(justify mirror)
			)
		)
		(duplicate_pad_numbers_are_jumpers no)
		(fp_line
			(start -0.299974 -0.150114)
			(end -0.299974 0.150114)
			(stroke
				(width 0.1)
				(type default)
			)
			(layer "B.Fab")
		)
		(fp_line
			(start -0.299974 0.150114)
			(end 0.299974 0.150114)
			(stroke
				(width 0.1)
				(type default)
			)
			(layer "B.Fab")
		)
		(fp_line
			(start 0.299974 -0.150114)
			(end -0.299974 -0.150114)
			(stroke
				(width 0.1)
				(type default)
			)
			(layer "B.Fab")
		)
		(fp_line
			(start 0.299974 0.150114)
			(end 0.299974 -0.150114)
			(stroke
				(width 0.1)
				(type default)
			)
			(layer "B.Fab")
		)
		(pad "1" smd rect
			(at 0.2667 0 180)
			(size 0.3048 0.381)
			(layers "B.Cu" "B.Mask" "B.Paste")
			(net "P1V8_PEX")
		)
		(pad "2" smd rect
			(at -0.2667 0 180)
			(size 0.3048 0.381)
			(layers "B.Cu" "B.Mask" "B.Paste")
			(net "GND")
		)
	)
	(footprint ""
		(layer "B.Cu")
		(at 176.699926 -303.499774 -90)
		(property "Reference" "C3089"
			(at 0 0 90)
			(layer "B.SilkS")
			(hide yes)
			(effects
				(font
					(size 1.27 1.27)
				)
				(justify mirror)
			)
		)
		(property "Value" ""
			(at 0 0 90)
			(layer "B.Fab")
			(effects
				(font
					(size 1.27 1.27)
				)
				(justify mirror)
			)
		)
		(duplicate_pad_numbers_are_jumpers no)
		(fp_line
			(start -0.299974 0.150114)
			(end 0.299974 0.150114)
			(stroke
				(width 0.1)
				(type default)
			)
			(layer "B.Fab")
		)
		(fp_line
			(start 0.299974 0.150114)
			(end 0.299974 -0.150114)
			(stroke
				(width 0.1)
				(type default)
			)
			(layer "B.Fab")
		)
		(fp_line
			(start -0.299974 -0.150114)
			(end -0.299974 0.150114)
			(stroke
				(width 0.1)
				(type default)
			)
			(layer "B.Fab")
		)
		(fp_line
			(start 0.299974 -0.150114)
			(end -0.299974 -0.150114)
			(stroke
				(width 0.1)
				(type default)
			)
			(layer "B.Fab")
		)
		(pad "1" smd rect
			(at 0.2667 0 90)
			(size 0.3048 0.381)
			(layers "B.Cu" "B.Mask" "B.Paste")
			(net "P1V25_PEX1")
		)
		(pad "2" smd rect
			(at -0.2667 0 90)
			(size 0.3048 0.381)
			(layers "B.Cu" "B.Mask" "B.Paste")
			(net "GND")
		)
	)
	(footprint ""
		(layer "B.Cu")
		(at 303.249838 -298.27474 180)
		(property "Reference" "C3277"
			(at 0 0 0)
			(layer "B.SilkS")
			(hide yes)
			(effects
				(font
					(size 1.27 1.27)
				)
				(justify mirror)
			)
		)
		(property "Value" ""
			(at 0 0 0)
			(layer "B.Fab")
			(effects
				(font
					(size 1.27 1.27)
				)
				(justify mirror)
			)
		)
		(duplicate_pad_numbers_are_jumpers no)
		(fp_line
			(start 0.299974 0.150114)
			(end 0.299974 -0.150114)
			(stroke
				(width 0.1)
				(type default)
			)
			(layer "B.Fab")
		)
		(fp_line
			(start 0.299974 -0.150114)
			(end -0.299974 -0.150114)
			(stroke
				(width 0.1)
				(type default)
			)
			(layer "B.Fab")
		)
		(fp_line
			(start -0.299974 0.150114)
			(end 0.299974 0.150114)
			(stroke
				(width 0.1)
				(type default)
			)
			(layer "B.Fab")
		)
		(fp_line
			(start -0.299974 -0.150114)
			(end -0.299974 0.150114)
			(stroke
				(width 0.1)
				(type default)
			)
			(layer "B.Fab")
		)
		(pad "1" smd rect
			(at 0.2667 0)
			(size 0.3048 0.381)
			(layers "B.Cu" "B.Mask" "B.Paste")
			(net "P1V25_PEX2")
		)
		(pad "2" smd rect
			(at -0.2667 0)
			(size 0.3048 0.381)
			(layers "B.Cu" "B.Mask" "B.Paste")
			(net "GND")
		)
	)
)
